(kicad_pcb
	(version 20260206)
	(generator "pcbnew")
	(generator_version "10.0")
	(general
		(thickness 1.6)
		(legacy_teardrops no)
	)
	(paper "A4")
	(title_block
		(title "03242023_DA0F0TMBIJ0_F0T_Motherboard_J_brd_V01_OCP.brd")
		(comment 1 "Grand Teton / footprint 3039 of 6105 (U2), pads 1063-1168 of 4677")
	)
	(layers
		(0 "F.Cu" signal "TOP")
		(4 "In1.Cu" signal "GND")
		(6 "In2.Cu" signal "IN1")
		(8 "In3.Cu" signal "GND1")
		(10 "In4.Cu" signal "IN2")
		(12 "In5.Cu" signal "GND2")
		(14 "In6.Cu" signal "IN3")
		(16 "In7.Cu" signal "GND3")
		(18 "In8.Cu" signal "VCC")
		(20 "In9.Cu" signal "VCC1")
		(22 "In10.Cu" signal "GND4")
		(24 "In11.Cu" signal "IN4")
		(26 "In12.Cu" signal "GND5")
		(28 "In13.Cu" signal "IN5")
		(30 "In14.Cu" signal "GND6")
		(32 "In15.Cu" signal "IN6")
		(34 "In16.Cu" signal "GND7")
		(2 "B.Cu" signal "BOTTOM")
		(9 "F.Adhes" user "F.Adhesive")
		(11 "B.Adhes" user "B.Adhesive")
		(13 "F.Paste" user "Package Geometry/Pastemask Top")
		(15 "B.Paste" user "Package Geometry/Pastemask Bottom")
		(5 "F.SilkS" user "Ref Des/Silkscreen Top")
		(7 "B.SilkS" user "Ref Des/Silkscreen Bottom")
		(1 "F.Mask" user "Board Geometry/Soldermask Top")
		(3 "B.Mask" user "Board Geometry/Soldermask Bottom")
		(17 "Dwgs.User" user "User.Drawings")
		(19 "Cmts.User" user "User.Comments")
		(21 "Eco1.User" user "User.Eco1")
		(23 "Eco2.User" user "User.Eco2")
		(25 "Edge.Cuts" user "Board Geometry/Outline")
		(27 "Margin" user)
		(31 "F.CrtYd" user "Package Geometry/Place Bound Top")
		(29 "B.CrtYd" user "Package Geometry/Place Bound Bottom")
		(35 "F.Fab" user "Ref Des/Assembly Top")
		(33 "B.Fab" user "Ref Des/Assembly Bottom")
	)
	(footprint ""
		(layer "F.Cu")
		(at 359.870248 -251.76988 90)
		(property "Reference" "U2"
			(at -74.416158 -44.488608 0)
			(unlocked yes)
			(layer "F.SilkS")
			(effects
				(font
					(size 1.6002 1.1938)
					(thickness 0.1524)
				)
				(justify left)
			)
		)
		(property "Value" ""
			(at 0 0 90)
			(layer "F.Fab")
			(effects
				(font
					(size 1.27 1.27)
				)
			)
		)
		(duplicate_pad_numbers_are_jumpers no)
		(pad "BE25" smd circle
			(at -17.89176 -6.398514 270)
			(size 0.4318 0.4318)
			(layers "F.Cu" "F.Mask" "F.Paste")
			(net "TP_I3C_MNG2_BMC_SW_SCL")
		)
		(pad "BE60" smd circle
			(at 12.19454 -6.288532 270)
			(size 0.4318 0.4318)
			(layers "F.Cu" "F.Mask" "F.Paste")
			(net "PVCCINFAON_CPU0")
		)
		(pad "BE62" smd circle
			(at 13.822426 -6.288532 270)
			(size 0.4318 0.4318)
			(layers "F.Cu" "F.Mask" "F.Paste")
			(net "TP_ESPI_IBL_CPU0_ALERT0_LVC1_N")
		)
		(pad "BE64" smd circle
			(at 15.450058 -6.288532 270)
			(size 0.4318 0.4318)
			(layers "F.Cu" "F.Mask" "F.Paste")
			(net "GND")
		)
		(pad "BE66" smd circle
			(at 17.07769 -6.288532 270)
			(size 0.4318 0.4318)
			(layers "F.Cu" "F.Mask" "F.Paste")
			(net "GND")
		)
		(pad "BE68" smd circle
			(at 18.705576 -6.288532 270)
			(size 0.4318 0.4318)
			(layers "F.Cu" "F.Mask" "F.Paste")
			(net "GND")
		)
		(pad "BE70" smd circle
			(at 20.333462 -6.288532 270)
			(size 0.4318 0.4318)
			(layers "F.Cu" "F.Mask" "F.Paste")
			(net "TP_TRC_CPU0_PTI<17>")
		)
		(pad "BE72" smd circle
			(at 21.961094 -6.288532 270)
			(size 0.4318 0.4318)
			(layers "F.Cu" "F.Mask" "F.Paste")
			(net "PVCCFA_EHV_FIVRA_CPU0")
		)
		(pad "BE74" smd circle
			(at 23.58898 -6.288532 270)
			(size 0.4318 0.4318)
			(layers "F.Cu" "F.Mask" "F.Paste")
			(net "GND")
		)
		(pad "BE76" smd circle
			(at 25.216612 -6.288532 270)
			(size 0.4318 0.4318)
			(layers "F.Cu" "F.Mask" "F.Paste")
			(net "GND")
		)
		(pad "BE78" smd circle
			(at 26.844498 -6.288532 270)
			(size 0.4318 0.4318)
			(layers "F.Cu" "F.Mask" "F.Paste")
			(net "GND")
		)
		(pad "BE80" smd circle
			(at 28.472384 -6.288532 270)
			(size 0.4318 0.4318)
			(layers "F.Cu" "F.Mask" "F.Paste")
			(net "UPI_CPU0_CPU1_P2P2_DP<1>")
		)
		(pad "BE82" smd circle
			(at 30.100016 -6.288532 270)
			(size 0.4318 0.4318)
			(layers "F.Cu" "F.Mask" "F.Paste")
			(net "UPI_CPU0_CPU1_P2P2_DN<4>")
		)
		(pad "BE84" smd circle
			(at 31.727902 -6.288532 270)
			(size 0.4318 0.4318)
			(layers "F.Cu" "F.Mask" "F.Paste")
			(net "GND")
		)
		(pad "BE86" smd circle
			(at 33.355534 -6.288532 270)
			(size 0.4318 0.4318)
			(layers "F.Cu" "F.Mask" "F.Paste")
			(net "PVCCIN_CPU0")
		)
		(pad "BE88" smd circle
			(at 34.98342 -6.288532 270)
			(size 0.4318 0.4318)
			(layers "F.Cu" "F.Mask" "F.Paste")
			(net "PVCCIN_CPU0")
		)
		(pad "BE90" smd circle
			(at 36.611306 -6.288532 270)
			(size 0.4318 0.4318)
			(layers "F.Cu" "F.Mask" "F.Paste")
			(net "PVCCIN_CPU0")
		)
		(pad "BF2" smd circle
			(at -36.611306 -5.928868 270)
			(size 0.4318 0.4318)
			(layers "F.Cu" "F.Mask" "F.Paste")
			(net "UPI_CPU0_CPU1_P0P1_DN<18>")
		)
		(pad "BF4" smd circle
			(at -34.98342 -5.928868 270)
			(size 0.4318 0.4318)
			(layers "F.Cu" "F.Mask" "F.Paste")
			(net "GND")
		)
		(pad "BF6" smd circle
			(at -33.355534 -5.928868 270)
			(size 0.4318 0.4318)
			(layers "F.Cu" "F.Mask" "F.Paste")
			(net "UPI_CPU1_CPU0_P1P0_DP<18>")
		)
		(pad "BF8" smd circle
			(at -31.727902 -5.928868 270)
			(size 0.4318 0.4318)
			(layers "F.Cu" "F.Mask" "F.Paste")
			(net "GND")
		)
		(pad "BF10" smd circle
			(at -30.100016 -5.928868 270)
			(size 0.4318 0.4318)
			(layers "F.Cu" "F.Mask" "F.Paste")
			(net "P5E_CPU0_PE1_RX_DN<14>")
		)
		(pad "BF12" smd circle
			(at -28.472384 -5.928868 270)
			(size 0.4318 0.4318)
			(layers "F.Cu" "F.Mask" "F.Paste")
			(net "GND")
		)
		(pad "BF14" smd circle
			(at -26.844498 -5.928868 270)
			(size 0.4318 0.4318)
			(layers "F.Cu" "F.Mask" "F.Paste")
			(net "P5E_CPU0_PE1_TX_DN<14>")
		)
		(pad "BF16" smd circle
			(at -25.216612 -5.928868 270)
			(size 0.4318 0.4318)
			(layers "F.Cu" "F.Mask" "F.Paste")
			(net "GND")
		)
		(pad "BF18" smd circle
			(at -23.58898 -5.928868 270)
			(size 0.4318 0.4318)
			(layers "F.Cu" "F.Mask" "F.Paste")
			(net "DMI_CPU0_PCH_RX_C_DN<2>")
		)
		(pad "BF20" smd circle
			(at -21.961094 -5.928868 270)
			(size 0.4318 0.4318)
			(layers "F.Cu" "F.Mask" "F.Paste")
			(net "GND")
		)
		(pad "BF22" smd circle
			(at -20.333462 -5.928868 270)
			(size 0.4318 0.4318)
			(layers "F.Cu" "F.Mask" "F.Paste")
			(net "H_CPU0_ERR0_LVC1_R_N")
		)
		(pad "BF24" smd circle
			(at -18.705576 -5.928868 270)
			(size 0.4318 0.4318)
			(layers "F.Cu" "F.Mask" "F.Paste")
			(net "TP_CPU0_IFST_TRIG_LVC1_R")
		)
		(pad "BF26" smd circle
			(at -17.07769 -5.928868 270)
			(size 0.4318 0.4318)
			(layers "F.Cu" "F.Mask" "F.Paste")
			(net "SVID_CLK1_CPU0")
		)
		(pad "BF61" smd circle
			(at 13.008356 -5.818886 270)
			(size 0.4318 0.4318)
			(layers "F.Cu" "F.Mask" "F.Paste")
			(net "GND")
		)
		(pad "BF63" smd circle
			(at 14.635988 -5.818886 270)
			(size 0.4318 0.4318)
			(layers "F.Cu" "F.Mask" "F.Paste")
			(net "GND")
		)
		(pad "BF65" smd circle
			(at 16.263874 -5.818886 270)
			(size 0.4318 0.4318)
			(layers "F.Cu" "F.Mask" "F.Paste")
			(net "TP_ESPI_IBL_CPU0_CS0_LVC1_N")
		)
		(pad "BF67" smd circle
			(at 17.89176 -5.818886 270)
			(size 0.4318 0.4318)
			(layers "F.Cu" "F.Mask" "F.Paste")
			(net "TP_TRC_CPU0_PTI2_CLK")
		)
		(pad "BF69" smd circle
			(at 19.519392 -5.818886 270)
			(size 0.4318 0.4318)
			(layers "F.Cu" "F.Mask" "F.Paste")
			(net "TP_TRC_CPU0_PTI<19>")
		)
		(pad "BF71" smd circle
			(at 21.147278 -5.818886 270)
			(size 0.4318 0.4318)
			(layers "F.Cu" "F.Mask" "F.Paste")
			(net "NC_CPU0_MDFI_DIE01_NS0")
		)
		(pad "BF73" smd circle
			(at 22.77491 -5.818886 270)
			(size 0.4318 0.4318)
			(layers "F.Cu" "F.Mask" "F.Paste")
			(net "GND")
		)
		(pad "BF75" smd circle
			(at 24.402796 -5.818886 270)
			(size 0.4318 0.4318)
			(layers "F.Cu" "F.Mask" "F.Paste")
			(net "GND")
		)
		(pad "BF77" smd circle
			(at 26.030682 -5.818886 270)
			(size 0.4318 0.4318)
			(layers "F.Cu" "F.Mask" "F.Paste")
			(net "PVCCFA_EHV_FIVRA_CPU0")
		)
		(pad "BF79" smd circle
			(at 27.658314 -5.818886 270)
			(size 0.4318 0.4318)
			(layers "F.Cu" "F.Mask" "F.Paste")
			(net "GND")
		)
		(pad "BF81" smd circle
			(at 29.2862 -5.818886 270)
			(size 0.4318 0.4318)
			(layers "F.Cu" "F.Mask" "F.Paste")
			(net "UPI_CPU0_CPU1_P2P2_DN<2>")
		)
		(pad "BF83" smd circle
			(at 30.914086 -5.818886 270)
			(size 0.4318 0.4318)
			(layers "F.Cu" "F.Mask" "F.Paste")
			(net "GND")
		)
		(pad "BF85" smd circle
			(at 32.541718 -5.818886 270)
			(size 0.4318 0.4318)
			(layers "F.Cu" "F.Mask" "F.Paste")
			(net "PVCCIN_CPU0")
		)
		(pad "BF87" smd circle
			(at 34.169604 -5.818886 270)
			(size 0.4318 0.4318)
			(layers "F.Cu" "F.Mask" "F.Paste")
			(net "PVCCIN_CPU0")
		)
		(pad "BF89" smd circle
			(at 35.797236 -5.818886 270)
			(size 0.4318 0.4318)
			(layers "F.Cu" "F.Mask" "F.Paste")
			(net "PVCCIN_CPU0")
		)
		(pad "BF91" smd oval
			(at 37.425122 -5.818886)
			(size 0.381 0.4826)
			(drill
				(offset 0 -0.0508)
			)
			(layers "F.Cu" "F.Mask" "F.Paste")
			(net "PVCCIN_CPU0")
		)
		(pad "BG1" smd oval
			(at -37.425122 -5.458714 180)
			(size 0.381 0.4826)
			(drill
				(offset 0 -0.0508)
			)
			(layers "F.Cu" "F.Mask" "F.Paste")
			(net "GND")
		)
		(pad "BG3" smd circle
			(at -35.797236 -5.458714 270)
			(size 0.4318 0.4318)
			(layers "F.Cu" "F.Mask" "F.Paste")
			(net "UPI_CPU0_CPU1_P0P1_DP<19>")
		)
		(pad "BG5" smd circle
			(at -34.169604 -5.458714 270)
			(size 0.4318 0.4318)
			(layers "F.Cu" "F.Mask" "F.Paste")
			(net "GND")
		)
		(pad "BG7" smd circle
			(at -32.541718 -5.458714 270)
			(size 0.4318 0.4318)
			(layers "F.Cu" "F.Mask" "F.Paste")
			(net "UPI_CPU1_CPU0_P1P0_DN<18>")
		)
		(pad "BG9" smd circle
			(at -30.914086 -5.458714 270)
			(size 0.4318 0.4318)
			(layers "F.Cu" "F.Mask" "F.Paste")
			(net "GND")
		)
		(pad "BG11" smd circle
			(at -29.2862 -5.458714 270)
			(size 0.4318 0.4318)
			(layers "F.Cu" "F.Mask" "F.Paste")
			(net "P5E_CPU0_PE1_RX_DN<13>")
		)
		(pad "BG13" smd circle
			(at -27.658314 -5.458714 270)
			(size 0.4318 0.4318)
			(layers "F.Cu" "F.Mask" "F.Paste")
			(net "GND")
		)
		(pad "BG15" smd circle
			(at -26.030682 -5.458714 270)
			(size 0.4318 0.4318)
			(layers "F.Cu" "F.Mask" "F.Paste")
			(net "P5E_CPU0_PE1_TX_DP<14>")
		)
		(pad "BG17" smd circle
			(at -24.402796 -5.458714 270)
			(size 0.4318 0.4318)
			(layers "F.Cu" "F.Mask" "F.Paste")
			(net "GND")
		)
		(pad "BG19" smd circle
			(at -22.77491 -5.458714 270)
			(size 0.4318 0.4318)
			(layers "F.Cu" "F.Mask" "F.Paste")
			(net "DMI_CPU0_PCH_RX_C_DP<2>")
		)
		(pad "BG21" smd circle
			(at -21.147278 -5.458714 270)
			(size 0.4318 0.4318)
			(layers "F.Cu" "F.Mask" "F.Paste")
			(net "GND")
		)
		(pad "BG23" smd circle
			(at -19.519392 -5.458714 270)
			(size 0.4318 0.4318)
			(layers "F.Cu" "F.Mask" "F.Paste")
			(net "GND")
		)
		(pad "BG25" smd circle
			(at -17.89176 -5.458714 270)
			(size 0.4318 0.4318)
			(layers "F.Cu" "F.Mask" "F.Paste")
			(net "GND")
		)
		(pad "BG60" smd circle
			(at 12.19454 -5.348732 270)
			(size 0.4318 0.4318)
			(layers "F.Cu" "F.Mask" "F.Paste")
			(net "PVCCINFAON_CPU0")
		)
		(pad "BG62" smd circle
			(at 13.822426 -5.348732 270)
			(size 0.4318 0.4318)
			(layers "F.Cu" "F.Mask" "F.Paste")
			(net "TP_CLK_66M_ESPI_IBL_CPU0_LVC1")
		)
		(pad "BG64" smd circle
			(at 15.450058 -5.348732 270)
			(size 0.4318 0.4318)
			(layers "F.Cu" "F.Mask" "F.Paste")
			(net "TP_RST_ESPI_IBL_CPU0_LVC1_N")
		)
		(pad "BG66" smd circle
			(at 17.07769 -5.348732 270)
			(size 0.4318 0.4318)
			(layers "F.Cu" "F.Mask" "F.Paste")
			(net "TP_TRC_CPU0_PTI<27>")
		)
		(pad "BG68" smd circle
			(at 18.705576 -5.348732 270)
			(size 0.4318 0.4318)
			(layers "F.Cu" "F.Mask" "F.Paste")
			(net "TP_TRC_CPU0_PTI<22>")
		)
		(pad "BG70" smd circle
			(at 20.333462 -5.348732 270)
			(size 0.4318 0.4318)
			(layers "F.Cu" "F.Mask" "F.Paste")
			(net "GND")
		)
		(pad "BG72" smd circle
			(at 21.961094 -5.348732 270)
			(size 0.4318 0.4318)
			(layers "F.Cu" "F.Mask" "F.Paste")
			(net "FM_CPU0_PROC_ID0")
		)
		(pad "BG74" smd circle
			(at 23.58898 -5.348732 270)
			(size 0.4318 0.4318)
			(layers "F.Cu" "F.Mask" "F.Paste")
			(net "UPI_CPU1_CPU0_P2P2_DP<3>")
		)
		(pad "BG76" smd circle
			(at 25.216612 -5.348732 270)
			(size 0.4318 0.4318)
			(layers "F.Cu" "F.Mask" "F.Paste")
			(net "UPI_CPU1_CPU0_P2P2_DP<6>")
		)
		(pad "BG78" smd circle
			(at 26.844498 -5.348732 270)
			(size 0.4318 0.4318)
			(layers "F.Cu" "F.Mask" "F.Paste")
			(net "NC_CPU0_HBM3_VIEWDIG0")
		)
		(pad "BG80" smd circle
			(at 28.472384 -5.348732 270)
			(size 0.4318 0.4318)
			(layers "F.Cu" "F.Mask" "F.Paste")
			(net "UPI_CPU0_CPU1_P2P2_DN<1>")
		)
		(pad "BG82" smd circle
			(at 30.100016 -5.348732 270)
			(size 0.4318 0.4318)
			(layers "F.Cu" "F.Mask" "F.Paste")
			(net "UPI_CPU0_CPU1_P2P2_DP<2>")
		)
		(pad "BG84" smd circle
			(at 31.727902 -5.348732 270)
			(size 0.4318 0.4318)
			(layers "F.Cu" "F.Mask" "F.Paste")
			(net "PVCCIN_CPU0")
		)
		(pad "BG86" smd circle
			(at 33.355534 -5.348732 270)
			(size 0.4318 0.4318)
			(layers "F.Cu" "F.Mask" "F.Paste")
			(net "PVCCIN_CPU0")
		)
		(pad "BG88" smd circle
			(at 34.98342 -5.348732 270)
			(size 0.4318 0.4318)
			(layers "F.Cu" "F.Mask" "F.Paste")
			(net "PVCCIN_CPU0")
		)
		(pad "BG90" smd circle
			(at 36.611306 -5.348732 270)
			(size 0.4318 0.4318)
			(layers "F.Cu" "F.Mask" "F.Paste")
			(net "PVCCIN_CPU0")
		)
		(pad "BH2" smd circle
			(at -36.611306 -4.989068 270)
			(size 0.4318 0.4318)
			(layers "F.Cu" "F.Mask" "F.Paste")
			(net "UPI_CPU0_CPU1_P0P1_DN<19>")
		)
		(pad "BH4" smd circle
			(at -34.98342 -4.989068 270)
			(size 0.4318 0.4318)
			(layers "F.Cu" "F.Mask" "F.Paste")
			(net "GND")
		)
		(pad "BH6" smd circle
			(at -33.355534 -4.989068 270)
			(size 0.4318 0.4318)
			(layers "F.Cu" "F.Mask" "F.Paste")
			(net "UPI_CPU1_CPU0_P1P0_DN<19>")
		)
		(pad "BH8" smd circle
			(at -31.727902 -4.989068 270)
			(size 0.4318 0.4318)
			(layers "F.Cu" "F.Mask" "F.Paste")
			(net "GND")
		)
		(pad "BH10" smd circle
			(at -30.100016 -4.989068 270)
			(size 0.4318 0.4318)
			(layers "F.Cu" "F.Mask" "F.Paste")
			(net "P5E_CPU0_PE1_RX_DP<13>")
		)
		(pad "BH12" smd circle
			(at -28.472384 -4.989068 270)
			(size 0.4318 0.4318)
			(layers "F.Cu" "F.Mask" "F.Paste")
			(net "GND")
		)
		(pad "BH14" smd circle
			(at -26.844498 -4.989068 270)
			(size 0.4318 0.4318)
			(layers "F.Cu" "F.Mask" "F.Paste")
			(net "P5E_CPU0_PE1_TX_DP<13>")
		)
		(pad "BH16" smd circle
			(at -25.216612 -4.989068 270)
			(size 0.4318 0.4318)
			(layers "F.Cu" "F.Mask" "F.Paste")
			(net "GND")
		)
		(pad "BH18" smd circle
			(at -23.58898 -4.989068 270)
			(size 0.4318 0.4318)
			(layers "F.Cu" "F.Mask" "F.Paste")
			(net "DMI_CPU0_PCH_RX_C_DN<3>")
		)
		(pad "BH20" smd circle
			(at -21.961094 -4.989068 270)
			(size 0.4318 0.4318)
			(layers "F.Cu" "F.Mask" "F.Paste")
			(net "GND")
		)
		(pad "BH22" smd circle
			(at -20.333462 -4.989068 270)
			(size 0.4318 0.4318)
			(layers "F.Cu" "F.Mask" "F.Paste")
			(net "H_CPU0_RMCA_LVC1_R_N")
		)
		(pad "BH24" smd circle
			(at -18.705576 -4.989068 270)
			(size 0.4318 0.4318)
			(layers "F.Cu" "F.Mask" "F.Paste")
			(net "PECI_CPU0_GTL_R")
		)
		(pad "BH26" smd circle
			(at -17.07769 -4.989068 270)
			(size 0.4318 0.4318)
			(layers "F.Cu" "F.Mask" "F.Paste")
			(net "SVID_CLK0_CPU0")
		)
		(pad "BH61" smd circle
			(at 13.008356 -4.879086 270)
			(size 0.4318 0.4318)
			(layers "F.Cu" "F.Mask" "F.Paste")
			(net "RST_CPU0_LVC1_N")
		)
		(pad "BH63" smd circle
			(at 14.635988 -4.879086 270)
			(size 0.4318 0.4318)
			(layers "F.Cu" "F.Mask" "F.Paste")
			(net "TP_ESPI_IBL_CPU0_OE_LVC1_N")
		)
		(pad "BH65" smd circle
			(at 16.263874 -4.879086 270)
			(size 0.4318 0.4318)
			(layers "F.Cu" "F.Mask" "F.Paste")
			(net "TP_ESPI_IBL_CPU0_CS1_N")
		)
		(pad "BH67" smd circle
			(at 17.89176 -4.879086 270)
			(size 0.4318 0.4318)
			(layers "F.Cu" "F.Mask" "F.Paste")
			(net "GND")
		)
		(pad "BH69" smd circle
			(at 19.519392 -4.879086 270)
			(size 0.4318 0.4318)
			(layers "F.Cu" "F.Mask" "F.Paste")
			(net "TP_TRC_CPU0_PTI<20>")
		)
		(pad "BH71" smd circle
			(at 21.147278 -4.879086 270)
			(size 0.4318 0.4318)
			(layers "F.Cu" "F.Mask" "F.Paste")
			(net "FM_CPU0_PROC_ID1")
		)
		(pad "BH73" smd circle
			(at 22.77491 -4.879086 270)
			(size 0.4318 0.4318)
			(layers "F.Cu" "F.Mask" "F.Paste")
			(net "GND")
		)
		(pad "BH75" smd circle
			(at 24.402796 -4.879086 270)
			(size 0.4318 0.4318)
			(layers "F.Cu" "F.Mask" "F.Paste")
			(net "UPI_CPU1_CPU0_P2P2_DN<6>")
		)
		(pad "BH77" smd circle
			(at 26.030682 -4.879086 270)
			(size 0.4318 0.4318)
			(layers "F.Cu" "F.Mask" "F.Paste")
			(net "GND")
		)
		(pad "BH79" smd circle
			(at 27.658314 -4.879086 270)
			(size 0.4318 0.4318)
			(layers "F.Cu" "F.Mask" "F.Paste")
			(net "PVCCFA_EHV_FIVRA_CPU0")
		)
		(pad "BH81" smd circle
			(at 29.2862 -4.879086 270)
			(size 0.4318 0.4318)
			(layers "F.Cu" "F.Mask" "F.Paste")
			(net "GND")
		)
		(pad "BH83" smd circle
			(at 30.914086 -4.879086 270)
			(size 0.4318 0.4318)
			(layers "F.Cu" "F.Mask" "F.Paste")
			(net "GND")
		)
		(pad "BH85" smd circle
			(at 32.541718 -4.879086 270)
			(size 0.4318 0.4318)
			(layers "F.Cu" "F.Mask" "F.Paste")
			(net "PVCCIN_CPU0")
		)
		(pad "BH87" smd circle
			(at 34.169604 -4.879086 270)
			(size 0.4318 0.4318)
			(layers "F.Cu" "F.Mask" "F.Paste")
			(net "PVCCIN_CPU0")
		)
		(pad "BH89" smd circle
			(at 35.797236 -4.879086 270)
			(size 0.4318 0.4318)
			(layers "F.Cu" "F.Mask" "F.Paste")
			(net "PVCCIN_CPU0")
		)
		(pad "BH91" smd oval
			(at 37.425122 -4.879086)
			(size 0.381 0.4826)
			(drill
				(offset 0 -0.0508)
			)
			(layers "F.Cu" "F.Mask" "F.Paste")
			(net "PVCCIN_CPU0")
		)
		(pad "BJ1" smd oval
			(at -37.425122 -4.518914 180)
			(size 0.381 0.4826)
			(drill
				(offset 0 -0.0508)
			)
			(layers "F.Cu" "F.Mask" "F.Paste")
			(net "UPI_CPU0_CPU1_P0P1_DN<20>")
		)
		(pad "BJ3" smd circle
			(at -35.797236 -4.518914 270)
			(size 0.4318 0.4318)
			(layers "F.Cu" "F.Mask" "F.Paste")
			(net "PVCCD_HV_CPU0")
		)
	)
)
